(kicad_pcb
	(version 20260206)
	(generator "pcbnew")
	(generator_version "10.0")
	(general
		(thickness 1.6)
		(legacy_teardrops no)
	)
	(paper "A4")
	(title_block
		(title "04192023_DAF0TMB3IC0_F0TG_MB_C_brd_V02_OCP.brd")
		(comment 1 "Grand Teton / footprints 7812-7820 of 8354")
	)
	(layers
		(0 "F.Cu" signal "TOP")
		(4 "In1.Cu" signal "GND")
		(6 "In2.Cu" signal "IN1")
		(8 "In3.Cu" signal "GND1")
		(10 "In4.Cu" signal "IN2")
		(12 "In5.Cu" signal "GND2")
		(14 "In6.Cu" signal "IN3")
		(16 "In7.Cu" signal "GND3")
		(18 "In8.Cu" signal "VCC")
		(20 "In9.Cu" signal "VCC1")
		(22 "In10.Cu" signal "GND4")
		(24 "In11.Cu" signal "IN4")
		(26 "In12.Cu" signal "GND5")
		(28 "In13.Cu" signal "IN5")
		(30 "In14.Cu" signal "GND6")
		(32 "In15.Cu" signal "IN6")
		(34 "In16.Cu" signal "GND7")
		(2 "B.Cu" signal "BOTTOM")
		(9 "F.Adhes" user "F.Adhesive")
		(11 "B.Adhes" user "B.Adhesive")
		(13 "F.Paste" user "Package Geometry/Pastemask Top")
		(15 "B.Paste" user "Package Geometry/Pastemask Bottom")
		(5 "F.SilkS" user "Ref Des/Silkscreen Top")
		(7 "B.SilkS" user "Ref Des/Silkscreen Bottom")
		(1 "F.Mask" user "Board Geometry/Soldermask Top")
		(3 "B.Mask" user "Board Geometry/Soldermask Bottom")
		(17 "Dwgs.User" user "User.Drawings")
		(19 "Cmts.User" user "User.Comments")
		(21 "Eco1.User" user "User.Eco1")
		(23 "Eco2.User" user "User.Eco2")
		(25 "Edge.Cuts" user "Board Geometry/Outline")
		(27 "Margin" user)
		(31 "F.CrtYd" user "Package Geometry/Place Bound Top")
		(29 "B.CrtYd" user "Package Geometry/Place Bound Bottom")
		(35 "F.Fab" user "Ref Des/Assembly Top")
		(33 "B.Fab" user "Ref Des/Assembly Bottom")
	)
	(footprint ""
		(layer "B.Cu")
		(at 229.8446 -340.868 180)
		(property "Reference" "R6755"
			(at 0 0 0)
			(layer "B.SilkS")
			(hide yes)
			(effects
				(font
					(size 1.27 1.27)
				)
				(justify mirror)
			)
		)
		(property "Value" ""
			(at 0 0 0)
			(layer "B.Fab")
			(effects
				(font
					(size 1.27 1.27)
				)
				(justify mirror)
			)
		)
		(duplicate_pad_numbers_are_jumpers no)
		(fp_line
			(start 0.32512 0.175006)
			(end 0.32512 -0.175006)
			(stroke
				(width 0.1)
				(type default)
			)
			(layer "B.Fab")
		)
		(fp_line
			(start 0.32512 -0.175006)
			(end -0.32512 -0.175006)
			(stroke
				(width 0.1)
				(type default)
			)
			(layer "B.Fab")
		)
		(fp_line
			(start -0.32512 0.175006)
			(end 0.32512 0.175006)
			(stroke
				(width 0.1)
				(type default)
			)
			(layer "B.Fab")
		)
		(fp_line
			(start -0.32512 -0.175006)
			(end -0.32512 0.175006)
			(stroke
				(width 0.1)
				(type default)
			)
			(layer "B.Fab")
		)
		(pad "1" smd rect
			(at 0.2667 0)
			(size 0.3048 0.381)
			(layers "B.Cu" "B.Mask" "B.Paste")
			(net "SMB_RT_CPU0_P0_SCL")
		)
		(pad "2" smd rect
			(at -0.2667 0 180)
			(size 0.3048 0.381)
			(layers "B.Cu" "B.Mask" "B.Paste")
			(net "SMB_RT_CPU0_P0_R_SCL")
		)
	)
	(footprint ""
		(layer "B.Cu")
		(at 147.947126 -408.517344 90)
		(property "Reference" "C6745"
			(at 0 0 90)
			(layer "B.SilkS")
			(hide yes)
			(effects
				(font
					(size 1.27 1.27)
				)
				(justify mirror)
			)
		)
		(property "Value" ""
			(at 0 0 90)
			(layer "B.Fab")
			(effects
				(font
					(size 1.27 1.27)
				)
				(justify mirror)
			)
		)
		(duplicate_pad_numbers_are_jumpers no)
		(fp_line
			(start 0.299974 -0.150114)
			(end -0.299974 -0.150114)
			(stroke
				(width 0.1)
				(type default)
			)
			(layer "B.Fab")
		)
		(fp_line
			(start -0.299974 -0.150114)
			(end -0.299974 0.150114)
			(stroke
				(width 0.1)
				(type default)
			)
			(layer "B.Fab")
		)
		(fp_line
			(start 0.299974 0.150114)
			(end 0.299974 -0.150114)
			(stroke
				(width 0.1)
				(type default)
			)
			(layer "B.Fab")
		)
		(fp_line
			(start -0.299974 0.150114)
			(end 0.299974 0.150114)
			(stroke
				(width 0.1)
				(type default)
			)
			(layer "B.Fab")
		)
		(pad "1" smd rect
			(at 0.2667 0 270)
			(size 0.3048 0.381)
			(layers "B.Cu" "B.Mask" "B.Paste")
			(net "P5E_CPU1_P3_TX_BUF_C_DP<10>")
		)
		(pad "2" smd rect
			(at -0.2667 0 270)
			(size 0.3048 0.381)
			(layers "B.Cu" "B.Mask" "B.Paste")
			(net "P5E_CPU1_P3_TX_BUF_DP<10>")
		)
	)
	(footprint ""
		(layer "B.Cu")
		(at 379.520958 -208.530952 90)
		(property "Reference" "C211"
			(at 0 0 90)
			(layer "B.SilkS")
			(hide yes)
			(effects
				(font
					(size 1.27 1.27)
				)
				(justify mirror)
			)
		)
		(property "Value" ""
			(at 0 0 90)
			(layer "B.Fab")
			(effects
				(font
					(size 1.27 1.27)
				)
				(justify mirror)
			)
		)
		(duplicate_pad_numbers_are_jumpers no)
		(fp_line
			(start 0.7874 -0.4064)
			(end -0.7874 -0.4064)
			(stroke
				(width 0.1524)
				(type default)
			)
			(layer "B.SilkS")
		)
		(fp_line
			(start -0.7874 -0.4064)
			(end -0.7874 0.4064)
			(stroke
				(width 0.1524)
				(type default)
			)
			(layer "B.SilkS")
		)
		(fp_line
			(start 0.7874 0.4064)
			(end 0.7874 -0.4064)
			(stroke
				(width 0.1524)
				(type default)
			)
			(layer "B.SilkS")
		)
		(fp_line
			(start -0.7874 0.4064)
			(end 0.7874 0.4064)
			(stroke
				(width 0.1524)
				(type default)
			)
			(layer "B.SilkS")
		)
		(fp_line
			(start 0.67945 -0.305054)
			(end 0.12065 -0.305054)
			(stroke
				(width 0.1)
				(type default)
			)
			(layer "B.Fab")
		)
		(fp_line
			(start 0.12065 -0.305054)
			(end 0.12065 -0.2794)
			(stroke
				(width 0.1)
				(type default)
			)
			(layer "B.Fab")
		)
		(fp_line
			(start -0.12065 -0.3048)
			(end -0.67945 -0.3048)
			(stroke
				(width 0.1)
				(type default)
			)
			(layer "B.Fab")
		)
		(fp_line
			(start -0.67945 -0.3048)
			(end -0.67945 0.3048)
			(stroke
				(width 0.1)
				(type default)
			)
			(layer "B.Fab")
		)
		(fp_line
			(start 0.12065 -0.2794)
			(end -0.12065 -0.2794)
			(stroke
				(width 0.1)
				(type default)
			)
			(layer "B.Fab")
		)
		(fp_line
			(start -0.12065 -0.2794)
			(end -0.12065 -0.3048)
			(stroke
				(width 0.1)
				(type default)
			)
			(layer "B.Fab")
		)
		(fp_line
			(start 0.12065 0.2794)
			(end 0.12065 0.3048)
			(stroke
				(width 0.1)
				(type default)
			)
			(layer "B.Fab")
		)
		(fp_line
			(start -0.120396 0.2794)
			(end 0.12065 0.2794)
			(stroke
				(width 0.1)
				(type default)
			)
			(layer "B.Fab")
		)
		(fp_line
			(start 0.67945 0.3048)
			(end 0.67945 -0.305054)
			(stroke
				(width 0.1)
				(type default)
			)
			(layer "B.Fab")
		)
		(fp_line
			(start 0.12065 0.3048)
			(end 0.67945 0.3048)
			(stroke
				(width 0.1)
				(type default)
			)
			(layer "B.Fab")
		)
		(fp_line
			(start -0.120396 0.3048)
			(end -0.120396 0.2794)
			(stroke
				(width 0.1)
				(type default)
			)
			(layer "B.Fab")
		)
		(fp_line
			(start -0.67945 0.3048)
			(end -0.120396 0.3048)
			(stroke
				(width 0.1)
				(type default)
			)
			(layer "B.Fab")
		)
		(pad "1" smd circle
			(at 0.40005 0 270)
			(size 0 0)
			(layers "B.Cu" "B.Mask" "B.Paste")
			(net "JTAG_CPU0_TMS")
		)
		(pad "2" smd circle
			(at -0.40005 0 270)
			(size 0 0)
			(layers "B.Cu" "B.Mask" "B.Paste")
			(net "GND")
		)
	)
	(footprint ""
		(layer "B.Cu")
		(at 331.639164 -136.474962 180)
		(property "Reference" "PR477"
			(at 0 0 0)
			(layer "B.SilkS")
			(hide yes)
			(effects
				(font
					(size 1.27 1.27)
				)
				(justify mirror)
			)
		)
		(property "Value" ""
			(at 0 0 0)
			(layer "B.Fab")
			(effects
				(font
					(size 1.27 1.27)
				)
				(justify mirror)
			)
		)
		(duplicate_pad_numbers_are_jumpers no)
		(fp_line
			(start 0.7874 0.4064)
			(end 0.7874 -0.4064)
			(stroke
				(width 0.1524)
				(type default)
			)
			(layer "B.SilkS")
		)
		(fp_line
			(start 0.7874 -0.4064)
			(end -0.7874 -0.4064)
			(stroke
				(width 0.1524)
				(type default)
			)
			(layer "B.SilkS")
		)
		(fp_line
			(start -0.7874 0.4064)
			(end 0.7874 0.4064)
			(stroke
				(width 0.1524)
				(type default)
			)
			(layer "B.SilkS")
		)
		(fp_line
			(start -0.7874 -0.4064)
			(end -0.7874 0.4064)
			(stroke
				(width 0.1524)
				(type default)
			)
			(layer "B.SilkS")
		)
		(fp_line
			(start 0.67945 0.3048)
			(end 0.67945 -0.305054)
			(stroke
				(width 0.1)
				(type default)
			)
			(layer "B.Fab")
		)
		(fp_line
			(start 0.67945 -0.305054)
			(end 0.12065 -0.305054)
			(stroke
				(width 0.1)
				(type default)
			)
			(layer "B.Fab")
		)
		(fp_line
			(start 0.12065 0.3048)
			(end 0.67945 0.3048)
			(stroke
				(width 0.1)
				(type default)
			)
			(layer "B.Fab")
		)
		(fp_line
			(start 0.12065 0.2794)
			(end 0.12065 0.3048)
			(stroke
				(width 0.1)
				(type default)
			)
			(layer "B.Fab")
		)
		(fp_line
			(start 0.12065 -0.2794)
			(end -0.12065 -0.2794)
			(stroke
				(width 0.1)
				(type default)
			)
			(layer "B.Fab")
		)
		(fp_line
			(start 0.12065 -0.305054)
			(end 0.12065 -0.2794)
			(stroke
				(width 0.1)
				(type default)
			)
			(layer "B.Fab")
		)
		(fp_line
			(start -0.120396 0.3048)
			(end -0.120396 0.2794)
			(stroke
				(width 0.1)
				(type default)
			)
			(layer "B.Fab")
		)
		(fp_line
			(start -0.120396 0.2794)
			(end 0.12065 0.2794)
			(stroke
				(width 0.1)
				(type default)
			)
			(layer "B.Fab")
		)
		(fp_line
			(start -0.12065 -0.2794)
			(end -0.12065 -0.3048)
			(stroke
				(width 0.1)
				(type default)
			)
			(layer "B.Fab")
		)
		(fp_line
			(start -0.12065 -0.3048)
			(end -0.67945 -0.3048)
			(stroke
				(width 0.1)
				(type default)
			)
			(layer "B.Fab")
		)
		(fp_line
			(start -0.67945 0.3048)
			(end -0.120396 0.3048)
			(stroke
				(width 0.1)
				(type default)
			)
			(layer "B.Fab")
		)
		(fp_line
			(start -0.67945 -0.3048)
			(end -0.67945 0.3048)
			(stroke
				(width 0.1)
				(type default)
			)
			(layer "B.Fab")
		)
		(pad "1" smd circle
			(at 0.40005 0)
			(size 0 0)
			(layers "B.Cu" "B.Mask" "B.Paste")
			(net "P3V3_AUX")
		)
		(pad "2" smd circle
			(at -0.40005 0)
			(size 0 0)
			(layers "B.Cu" "B.Mask" "B.Paste")
			(net "PVDD18_S5_P0_VCC")
		)
	)
	(footprint ""
		(layer "B.Cu")
		(at 393.602718 -323.692012)
		(property "Reference" "R468"
			(at 0 0 0)
			(layer "B.SilkS")
			(hide yes)
			(effects
				(font
					(size 1.27 1.27)
				)
				(justify mirror)
			)
		)
		(property "Value" ""
			(at 0 0 0)
			(layer "B.Fab")
			(effects
				(font
					(size 1.27 1.27)
				)
				(justify mirror)
			)
		)
		(duplicate_pad_numbers_are_jumpers no)
		(fp_line
			(start -0.7874 -0.4064)
			(end -0.7874 0.4064)
			(stroke
				(width 0.1524)
				(type default)
			)
			(layer "B.SilkS")
		)
		(fp_line
			(start -0.7874 0.4064)
			(end 0.7874 0.4064)
			(stroke
				(width 0.1524)
				(type default)
			)
			(layer "B.SilkS")
		)
		(fp_line
			(start 0.7874 -0.4064)
			(end -0.7874 -0.4064)
			(stroke
				(width 0.1524)
				(type default)
			)
			(layer "B.SilkS")
		)
		(fp_line
			(start 0.7874 0.4064)
			(end 0.7874 -0.4064)
			(stroke
				(width 0.1524)
				(type default)
			)
			(layer "B.SilkS")
		)
		(fp_line
			(start -0.67945 -0.3048)
			(end -0.67945 0.3048)
			(stroke
				(width 0.1)
				(type default)
			)
			(layer "B.Fab")
		)
		(fp_line
			(start -0.67945 0.3048)
			(end -0.120396 0.3048)
			(stroke
				(width 0.1)
				(type default)
			)
			(layer "B.Fab")
		)
		(fp_line
			(start -0.12065 -0.3048)
			(end -0.67945 -0.3048)
			(stroke
				(width 0.1)
				(type default)
			)
			(layer "B.Fab")
		)
		(fp_line
			(start -0.12065 -0.2794)
			(end -0.12065 -0.3048)
			(stroke
				(width 0.1)
				(type default)
			)
			(layer "B.Fab")
		)
		(fp_line
			(start -0.120396 0.2794)
			(end 0.12065 0.2794)
			(stroke
				(width 0.1)
				(type default)
			)
			(layer "B.Fab")
		)
		(fp_line
			(start -0.120396 0.3048)
			(end -0.120396 0.2794)
			(stroke
				(width 0.1)
				(type default)
			)
			(layer "B.Fab")
		)
		(fp_line
			(start 0.12065 -0.305054)
			(end 0.12065 -0.2794)
			(stroke
				(width 0.1)
				(type default)
			)
			(layer "B.Fab")
		)
		(fp_line
			(start 0.12065 -0.2794)
			(end -0.12065 -0.2794)
			(stroke
				(width 0.1)
				(type default)
			)
			(layer "B.Fab")
		)
		(fp_line
			(start 0.12065 0.2794)
			(end 0.12065 0.3048)
			(stroke
				(width 0.1)
				(type default)
			)
			(layer "B.Fab")
		)
		(fp_line
			(start 0.12065 0.3048)
			(end 0.67945 0.3048)
			(stroke
				(width 0.1)
				(type default)
			)
			(layer "B.Fab")
		)
		(fp_line
			(start 0.67945 -0.305054)
			(end 0.12065 -0.305054)
			(stroke
				(width 0.1)
				(type default)
			)
			(layer "B.Fab")
		)
		(fp_line
			(start 0.67945 0.3048)
			(end 0.67945 -0.305054)
			(stroke
				(width 0.1)
				(type default)
			)
			(layer "B.Fab")
		)
		(pad "1" smd circle
			(at 0.40005 0 180)
			(size 0 0)
			(layers "B.Cu" "B.Mask" "B.Paste")
			(net "ESPI_CPU0_D0")
		)
		(pad "2" smd circle
			(at -0.40005 0 180)
			(size 0 0)
			(layers "B.Cu" "B.Mask" "B.Paste")
			(net "ESPI_CPU0_R_D0")
		)
	)
	(footprint ""
		(layer "B.Cu")
		(at 233.172 -336.296 180)
		(property "Reference" "R1109"
			(at 0 0 0)
			(layer "B.SilkS")
			(hide yes)
			(effects
				(font
					(size 1.27 1.27)
				)
				(justify mirror)
			)
		)
		(property "Value" ""
			(at 0 0 0)
			(layer "B.Fab")
			(effects
				(font
					(size 1.27 1.27)
				)
				(justify mirror)
			)
		)
		(duplicate_pad_numbers_are_jumpers no)
		(fp_line
			(start 0.32512 0.175006)
			(end 0.32512 -0.175006)
			(stroke
				(width 0.1)
				(type default)
			)
			(layer "B.Fab")
		)
		(fp_line
			(start 0.32512 -0.175006)
			(end -0.32512 -0.175006)
			(stroke
				(width 0.1)
				(type default)
			)
			(layer "B.Fab")
		)
		(fp_line
			(start -0.32512 0.175006)
			(end 0.32512 0.175006)
			(stroke
				(width 0.1)
				(type default)
			)
			(layer "B.Fab")
		)
		(fp_line
			(start -0.32512 -0.175006)
			(end -0.32512 0.175006)
			(stroke
				(width 0.1)
				(type default)
			)
			(layer "B.Fab")
		)
		(pad "1" smd rect
			(at 0.2667 0)
			(size 0.3048 0.381)
			(layers "B.Cu" "B.Mask" "B.Paste")
			(net "SMB_RT_CPU0_P3_R_SCL")
		)
		(pad "2" smd rect
			(at -0.2667 0 180)
			(size 0.3048 0.381)
			(layers "B.Cu" "B.Mask" "B.Paste")
			(net "SMB_RT_CPU0_P3_R2_SCL")
		)
	)
	(footprint ""
		(layer "B.Cu")
		(at 456.690476 -45.978826 -90)
		(property "Reference" "R3117"
			(at 0 0 90)
			(layer "B.SilkS")
			(hide yes)
			(effects
				(font
					(size 1.27 1.27)
				)
				(justify mirror)
			)
		)
		(property "Value" ""
			(at 0 0 90)
			(layer "B.Fab")
			(effects
				(font
					(size 1.27 1.27)
				)
				(justify mirror)
			)
		)
		(duplicate_pad_numbers_are_jumpers no)
		(fp_line
			(start -0.7874 0.4064)
			(end 0.7874 0.4064)
			(stroke
				(width 0.1524)
				(type default)
			)
			(layer "B.SilkS")
		)
		(fp_line
			(start 0.7874 0.4064)
			(end 0.7874 -0.4064)
			(stroke
				(width 0.1524)
				(type default)
			)
			(layer "B.SilkS")
		)
		(fp_line
			(start -0.7874 -0.4064)
			(end -0.7874 0.4064)
			(stroke
				(width 0.1524)
				(type default)
			)
			(layer "B.SilkS")
		)
		(fp_line
			(start 0.7874 -0.4064)
			(end -0.7874 -0.4064)
			(stroke
				(width 0.1524)
				(type default)
			)
			(layer "B.SilkS")
		)
		(fp_line
			(start -0.67945 0.3048)
			(end -0.120396 0.3048)
			(stroke
				(width 0.1)
				(type default)
			)
			(layer "B.Fab")
		)
		(fp_line
			(start -0.120396 0.3048)
			(end -0.120396 0.2794)
			(stroke
				(width 0.1)
				(type default)
			)
			(layer "B.Fab")
		)
		(fp_line
			(start 0.12065 0.3048)
			(end 0.67945 0.3048)
			(stroke
				(width 0.1)
				(type default)
			)
			(layer "B.Fab")
		)
		(fp_line
			(start 0.67945 0.3048)
			(end 0.67945 -0.305054)
			(stroke
				(width 0.1)
				(type default)
			)
			(layer "B.Fab")
		)
		(fp_line
			(start -0.120396 0.2794)
			(end 0.12065 0.2794)
			(stroke
				(width 0.1)
				(type default)
			)
			(layer "B.Fab")
		)
		(fp_line
			(start 0.12065 0.2794)
			(end 0.12065 0.3048)
			(stroke
				(width 0.1)
				(type default)
			)
			(layer "B.Fab")
		)
		(fp_line
			(start -0.12065 -0.2794)
			(end -0.12065 -0.3048)
			(stroke
				(width 0.1)
				(type default)
			)
			(layer "B.Fab")
		)
		(fp_line
			(start 0.12065 -0.2794)
			(end -0.12065 -0.2794)
			(stroke
				(width 0.1)
				(type default)
			)
			(layer "B.Fab")
		)
		(fp_line
			(start -0.67945 -0.3048)
			(end -0.67945 0.3048)
			(stroke
				(width 0.1)
				(type default)
			)
			(layer "B.Fab")
		)
		(fp_line
			(start -0.12065 -0.3048)
			(end -0.67945 -0.3048)
			(stroke
				(width 0.1)
				(type default)
			)
			(layer "B.Fab")
		)
		(fp_line
			(start 0.12065 -0.305054)
			(end 0.12065 -0.2794)
			(stroke
				(width 0.1)
				(type default)
			)
			(layer "B.Fab")
		)
		(fp_line
			(start 0.67945 -0.305054)
			(end 0.12065 -0.305054)
			(stroke
				(width 0.1)
				(type default)
			)
			(layer "B.Fab")
		)
		(pad "1" smd circle
			(at 0.40005 0 90)
			(size 0 0)
			(layers "B.Cu" "B.Mask" "B.Paste")
			(net "P12V_AUX")
		)
		(pad "2" smd circle
			(at -0.40005 0 90)
			(size 0 0)
			(layers "B.Cu" "B.Mask" "B.Paste")
			(net "P3V3_AUX_EN")
		)
	)
	(footprint ""
		(layer "B.Cu")
		(at 67.679824 -408.517344 90)
		(property "Reference" "C6674"
			(at 0 0 90)
			(layer "B.SilkS")
			(hide yes)
			(effects
				(font
					(size 1.27 1.27)
				)
				(justify mirror)
			)
		)
		(property "Value" ""
			(at 0 0 90)
			(layer "B.Fab")
			(effects
				(font
					(size 1.27 1.27)
				)
				(justify mirror)
			)
		)
		(duplicate_pad_numbers_are_jumpers no)
		(fp_line
			(start 0.299974 -0.150114)
			(end -0.299974 -0.150114)
			(stroke
				(width 0.1)
				(type default)
			)
			(layer "B.Fab")
		)
		(fp_line
			(start -0.299974 -0.150114)
			(end -0.299974 0.150114)
			(stroke
				(width 0.1)
				(type default)
			)
			(layer "B.Fab")
		)
		(fp_line
			(start 0.299974 0.150114)
			(end 0.299974 -0.150114)
			(stroke
				(width 0.1)
				(type default)
			)
			(layer "B.Fab")
		)
		(fp_line
			(start -0.299974 0.150114)
			(end 0.299974 0.150114)
			(stroke
				(width 0.1)
				(type default)
			)
			(layer "B.Fab")
		)
		(pad "1" smd rect
			(at 0.2667 0 270)
			(size 0.3048 0.381)
			(layers "B.Cu" "B.Mask" "B.Paste")
			(net "P5E_CPU1_P1_TX_BUF_C_DN<6>")
		)
		(pad "2" smd rect
			(at -0.2667 0 270)
			(size 0.3048 0.381)
			(layers "B.Cu" "B.Mask" "B.Paste")
			(net "P5E_CPU1_P1_TX_BUF_DN<6>")
		)
	)
	(footprint ""
		(layer "B.Cu")
		(at 233.807 -339.598 180)
		(property "Reference" "R1026"
			(at 0 0 0)
			(layer "B.SilkS")
			(hide yes)
			(effects
				(font
					(size 1.27 1.27)
				)
				(justify mirror)
			)
		)
		(property "Value" ""
			(at 0 0 0)
			(layer "B.Fab")
			(effects
				(font
					(size 1.27 1.27)
				)
				(justify mirror)
			)
		)
		(duplicate_pad_numbers_are_jumpers no)
		(fp_line
			(start 0.32512 0.175006)
			(end 0.32512 -0.175006)
			(stroke
				(width 0.1)
				(type default)
			)
			(layer "B.Fab")
		)
		(fp_line
			(start 0.32512 -0.175006)
			(end -0.32512 -0.175006)
			(stroke
				(width 0.1)
				(type default)
			)
			(layer "B.Fab")
		)
		(fp_line
			(start -0.32512 0.175006)
			(end 0.32512 0.175006)
			(stroke
				(width 0.1)
				(type default)
			)
			(layer "B.Fab")
		)
		(fp_line
			(start -0.32512 -0.175006)
			(end -0.32512 0.175006)
			(stroke
				(width 0.1)
				(type default)
			)
			(layer "B.Fab")
		)
		(pad "1" smd rect
			(at 0.2667 0)
			(size 0.3048 0.381)
			(layers "B.Cu" "B.Mask" "B.Paste")
			(net "SMB_RT_CPU0_P1_R_SDA")
		)
		(pad "2" smd rect
			(at -0.2667 0 180)
			(size 0.3048 0.381)
			(layers "B.Cu" "B.Mask" "B.Paste")
			(net "SMB_RT_CPU0_P1_R2_SDA")
		)
	)
)
